# S9S_MB_2U (Grand Teton) — schematic netlist excerpt (pin names and nets, part order shuffled) for the footprints in the layout excerpt that follows; sources: Cadence DE-HDL packaged netlist, KiCad conversion of 03242023_DA0F0TMBIJ0_F0T_Motherboard_J_brd_V01_OCP.brd

R3109  Q_RES  0 5% CHIP  pkg 0402LF  page 234 : A = SMB_1_BMC_GPU_SCL ; B = SMB_1_BMC_GPU_R_SCL
D74  Q_LED  IC  pkg SMLF  page 253 : A = LED_PWRGD_PVPP_HBM_CPU0 ; C = LED_PWRGD_PVPP_HBM_CPU0_D

(kicad_pcb
	(version 20260206)
	(generator "pcbnew")
	(generator_version "10.0")
	(general
		(thickness 1.6)
		(legacy_teardrops no)
	)
	(paper "A4")
	(title_block
		(title "03242023_DA0F0TMBIJ0_F0T_Motherboard_J_brd_V01_OCP.brd")
		(comment 1 "Grand Teton / footprints 3393-3394 of 6105")
	)
	(layers
		(0 "F.Cu" signal "TOP")
		(4 "In1.Cu" signal "GND")
		(6 "In2.Cu" signal "IN1")
		(8 "In3.Cu" signal "GND1")
		(10 "In4.Cu" signal "IN2")
		(12 "In5.Cu" signal "GND2")
		(14 "In6.Cu" signal "IN3")
		(16 "In7.Cu" signal "GND3")
		(18 "In8.Cu" signal "VCC")
		(20 "In9.Cu" signal "VCC1")
		(22 "In10.Cu" signal "GND4")
		(24 "In11.Cu" signal "IN4")
		(26 "In12.Cu" signal "GND5")
		(28 "In13.Cu" signal "IN5")
		(30 "In14.Cu" signal "GND6")
		(32 "In15.Cu" signal "IN6")
		(34 "In16.Cu" signal "GND7")
		(2 "B.Cu" signal "BOTTOM")
		(9 "F.Adhes" user "F.Adhesive")
		(11 "B.Adhes" user "B.Adhesive")
		(13 "F.Paste" user "Package Geometry/Pastemask Top")
		(15 "B.Paste" user "Package Geometry/Pastemask Bottom")
		(5 "F.SilkS" user "Ref Des/Silkscreen Top")
		(7 "B.SilkS" user "Ref Des/Silkscreen Bottom")
		(1 "F.Mask" user "Board Geometry/Soldermask Top")
		(3 "B.Mask" user "Board Geometry/Soldermask Bottom")
		(17 "Dwgs.User" user "User.Drawings")
		(19 "Cmts.User" user "User.Comments")
		(21 "Eco1.User" user "User.Eco1")
		(23 "Eco2.User" user "User.Eco2")
		(25 "Edge.Cuts" user "Board Geometry/Outline")
		(27 "Margin" user)
		(31 "F.CrtYd" user "Package Geometry/Place Bound Top")
		(29 "B.CrtYd" user "Package Geometry/Place Bound Bottom")
		(35 "F.Fab" user "Ref Des/Assembly Top")
		(33 "B.Fab" user "Ref Des/Assembly Bottom")
	)
	(footprint ""
		(layer "F.Cu")
		(at 77.595476 -79.078836)
		(property "Reference" "D74"
			(at -40.11041 34.331402 90)
			(unlocked yes)
			(layer "F.SilkS")
			(effects
				(font
					(size 0.635 0.4064)
					(thickness 0.1524)
				)
				(justify left)
			)
		)
		(property "Value" ""
			(at 0 0 0)
			(layer "F.Fab")
			(effects
				(font
					(size 1.27 1.27)
				)
			)
		)
		(duplicate_pad_numbers_are_jumpers no)
		(fp_line
			(start -0.90678 0.4826)
			(end -0.90678 -0.4699)
			(stroke
				(width 0.1524)
				(type default)
			)
			(layer "F.SilkS")
		)
		(fp_line
			(start -0.89408 -0.4826)
			(end 0.90678 -0.4826)
			(stroke
				(width 0.1524)
				(type default)
			)
			(layer "F.SilkS")
		)
		(fp_line
			(start -0.79248 -0.4826)
			(end 1.03378 -0.4826)
			(stroke
				(width 0.1524)
				(type default)
			)
			(layer "F.SilkS")
		)
		(fp_line
			(start -0.64008 -0.4826)
			(end 1.16078 -0.4826)
			(stroke
				(width 0.1524)
				(type default)
			)
			(layer "F.SilkS")
		)
		(fp_line
			(start 0.90678 -0.4826)
			(end 0.90678 0.4826)
			(stroke
				(width 0.1524)
				(type default)
			)
			(layer "F.SilkS")
		)
		(fp_line
			(start 0.90678 0.4826)
			(end -0.90678 0.4826)
			(stroke
				(width 0.1524)
				(type default)
			)
			(layer "F.SilkS")
		)
		(fp_line
			(start 1.03378 -0.4826)
			(end 1.03378 0.4826)
			(stroke
				(width 0.1524)
				(type default)
			)
			(layer "F.SilkS")
		)
		(fp_line
			(start 1.03378 0.4826)
			(end -0.79248 0.4826)
			(stroke
				(width 0.1524)
				(type default)
			)
			(layer "F.SilkS")
		)
		(fp_line
			(start 1.16078 -0.4826)
			(end 1.16078 0.4826)
			(stroke
				(width 0.1524)
				(type default)
			)
			(layer "F.SilkS")
		)
		(fp_line
			(start 1.16078 0.4826)
			(end -0.64008 0.4826)
			(stroke
				(width 0.1524)
				(type default)
			)
			(layer "F.SilkS")
		)
		(fp_line
			(start -0.499872 -0.249936)
			(end 0.499872 -0.249936)
			(stroke
				(width 0.1)
				(type default)
			)
			(layer "F.Fab")
		)
		(fp_line
			(start -0.499872 0.249936)
			(end -0.499872 -0.249936)
			(stroke
				(width 0.1)
				(type default)
			)
			(layer "F.Fab")
		)
		(fp_line
			(start 0.499872 -0.249936)
			(end 0.499872 0.249936)
			(stroke
				(width 0.1)
				(type default)
			)
			(layer "F.Fab")
		)
		(fp_line
			(start 0.499872 0.249936)
			(end -0.499872 0.249936)
			(stroke
				(width 0.1)
				(type default)
			)
			(layer "F.Fab")
		)
		(pad "A" smd rect
			(at -0.47498 0)
			(size 0.6096 0.7112)
			(layers "F.Cu" "F.Mask" "F.Paste")
			(net "LED_PWRGD_PVPP_HBM_CPU0")
		)
		(pad "C" smd rect
			(at 0.47498 0)
			(size 0.6096 0.7112)
			(layers "F.Cu" "F.Mask" "F.Paste")
			(net "LED_PWRGD_PVPP_HBM_CPU0_D")
		)
	)
	(footprint ""
		(layer "F.Cu")
		(at 38.02888 -433.923948)
		(property "Reference" "R3109"
			(at 0 0 0)
			(layer "F.SilkS")
			(hide yes)
			(effects
				(font
					(size 1.27 1.27)
				)
			)
		)
		(property "Value" ""
			(at 0 0 0)
			(layer "F.Fab")
			(effects
				(font
					(size 1.27 1.27)
				)
			)
		)
		(duplicate_pad_numbers_are_jumpers no)
		(fp_line
			(start -0.7874 -0.4064)
			(end 0.7874 -0.4064)
			(stroke
				(width 0.1524)
				(type default)
			)
			(layer "F.SilkS")
		)
		(fp_line
			(start -0.7874 0.4064)
			(end -0.7874 -0.4064)
			(stroke
				(width 0.1524)
				(type default)
			)
			(layer "F.SilkS")
		)
		(fp_line
			(start 0.7874 -0.4064)
			(end 0.7874 0.4064)
			(stroke
				(width 0.1524)
				(type default)
			)
			(layer "F.SilkS")
		)
		(fp_line
			(start 0.7874 0.4064)
			(end -0.7874 0.4064)
			(stroke
				(width 0.1524)
				(type default)
			)
			(layer "F.SilkS")
		)
		(fp_line
			(start -0.67945 -0.305054)
			(end -0.12065 -0.305054)
			(stroke
				(width 0.1)
				(type default)
			)
			(layer "F.Fab")
		)
		(fp_line
			(start -0.67945 0.3048)
			(end -0.67945 -0.305054)
			(stroke
				(width 0.1)
				(type default)
			)
			(layer "F.Fab")
		)
		(fp_line
			(start -0.12065 -0.305054)
			(end -0.12065 -0.2794)
			(stroke
				(width 0.1)
				(type default)
			)
			(layer "F.Fab")
		)
		(fp_line
			(start -0.12065 -0.2794)
			(end 0.12065 -0.2794)
			(stroke
				(width 0.1)
				(type default)
			)
			(layer "F.Fab")
		)
		(fp_line
			(start -0.12065 0.2794)
			(end -0.12065 0.3048)
			(stroke
				(width 0.1)
				(type default)
			)
			(layer "F.Fab")
		)
		(fp_line
			(start -0.12065 0.3048)
			(end -0.67945 0.3048)
			(stroke
				(width 0.1)
				(type default)
			)
			(layer "F.Fab")
		)
		(fp_line
			(start 0.120396 0.2794)
			(end -0.12065 0.2794)
			(stroke
				(width 0.1)
				(type default)
			)
			(layer "F.Fab")
		)
		(fp_line
			(start 0.120396 0.3048)
			(end 0.120396 0.2794)
			(stroke
				(width 0.1)
				(type default)
			)
			(layer "F.Fab")
		)
		(fp_line
			(start 0.12065 -0.3048)
			(end 0.67945 -0.3048)
			(stroke
				(width 0.1)
				(type default)
			)
			(layer "F.Fab")
		)
		(fp_line
			(start 0.12065 -0.2794)
			(end 0.12065 -0.3048)
			(stroke
				(width 0.1)
				(type default)
			)
			(layer "F.Fab")
		)
		(fp_line
			(start 0.67945 -0.3048)
			(end 0.67945 0.3048)
			(stroke
				(width 0.1)
				(type default)
			)
			(layer "F.Fab")
		)
		(fp_line
			(start 0.67945 0.3048)
			(end 0.120396 0.3048)
			(stroke
				(width 0.1)
				(type default)
			)
			(layer "F.Fab")
		)
		(pad "1" smd circle
			(at -0.40005 0)
			(size 0 0)
			(layers "F.Cu" "F.Mask" "F.Paste")
			(net "SMB_1_BMC_GPU_SCL")
		)
		(pad "2" smd circle
			(at 0.40005 0)
			(size 0 0)
			(layers "F.Cu" "F.Mask" "F.Paste")
			(net "SMB_1_BMC_GPU_R_SCL")
		)
	)
)
